(kicad_pcb
	(version 20241229)
	(generator "pcbnew")
	(generator_version "9.0")
	(general
		(thickness 1.599998)
		(legacy_teardrops no)
	)
	(paper "A4")
	(title_block
		(date "2023-02-12")
		(rev "1.1.5")
		(comment 9 "footprints 165-172 of 473")
	)
	(layers
		(0 "F.Cu" signal)
		(4 "In1.Cu" power "In1.GND")
		(6 "In2.Cu" signal)
		(8 "In3.Cu" power "In3.GND")
		(10 "In4.Cu" power "In4.VCC")
		(12 "In5.Cu" signal)
		(14 "In6.Cu" power "In6.VCC")
		(2 "B.Cu" signal)
		(9 "F.Adhes" user "F.Adhesive")
		(11 "B.Adhes" user "B.Adhesive")
		(13 "F.Paste" user)
		(15 "B.Paste" user)
		(5 "F.SilkS" user "F.Silkscreen")
		(7 "B.SilkS" user "B.Silkscreen")
		(1 "F.Mask" user)
		(3 "B.Mask" user)
		(17 "Dwgs.User" user "User.Drawings")
		(19 "Cmts.User" user "User.Comments")
		(21 "Eco1.User" user "User.Eco1")
		(23 "Eco2.User" user "User.Eco2")
		(25 "Edge.Cuts" user)
		(27 "Margin" user)
		(31 "F.CrtYd" user "F.Courtyard")
		(29 "B.CrtYd" user "B.Courtyard")
		(35 "F.Fab" user)
		(33 "B.Fab" user)
	)
	(footprint "antmicro-footprints:R_0402_1005Metric"
		(layer "F.Cu")
		(at 128.672157 55.688672)
		(descr "Resistor SMD 0402")
		(tags "resistor SMD 0402")
		(property "Reference" "R115"
			(at -1.272157 -0.688672 0)
			(layer "F.SilkS")
			(effects
				(font
					(size 0.7 0.7)
					(thickness 0.15)
				)
				(justify left bottom)
			)
		)
		(property "Value" "R_5R1_0402"
			(at 0 1.4 0)
			(layer "F.Fab")
			(effects
				(font
					(size 0.7 0.7)
					(thickness 0.15)
				)
				(justify left bottom)
			)
		)
		(property "Description" "5R1 resistor in 0402 package with 1% tolerance"
			(at 0 0 0)
			(layer "F.Fab")
			(hide yes)
			(effects
				(font
					(size 1.27 1.27)
					(thickness 0.15)
				)
			)
		)
		(property "Author" "Antmicro"
			(at 0 0 0)
			(layer "F.Fab")
			(hide yes)
			(effects
				(font
					(size 1 1)
					(thickness 0.15)
				)
			)
		)
		(property "License" "Apache-2.0"
			(at 0 0 0)
			(layer "F.Fab")
			(hide yes)
			(effects
				(font
					(size 1 1)
					(thickness 0.15)
				)
			)
		)
		(property "MPN" "CR0402-FX-5R10GLF"
			(at 0 0 0)
			(layer "F.Fab")
			(hide yes)
			(effects
				(font
					(size 1 1)
					(thickness 0.15)
				)
			)
		)
		(property "Manufacturer" "Bourns"
			(at 0 0 0)
			(layer "F.Fab")
			(hide yes)
			(effects
				(font
					(size 1 1)
					(thickness 0.15)
				)
			)
		)
		(property "Tolerance" "1%"
			(at 0 0 0)
			(layer "F.Fab")
			(hide yes)
			(effects
				(font
					(size 1 1)
					(thickness 0.15)
				)
			)
		)
		(property "Val" "5R1"
			(at 0 0 0)
			(layer "F.Fab")
			(hide yes)
			(effects
				(font
					(size 1 1)
					(thickness 0.15)
				)
			)
		)
		(sheetname "Supply")
		(sheetfile "supply.kicad_sch")
		(attr exclude_from_pos_files exclude_from_bom dnp)
		(fp_rect
			(start -0.93 -0.47)
			(end 0.93 0.47)
			(stroke
				(width 0.05)
				(type solid)
			)
			(fill no)
			(layer "F.CrtYd")
		)
		(fp_rect
			(start -0.5 -0.25)
			(end 0.5 0.25)
			(stroke
				(width 0.15)
				(type solid)
			)
			(fill no)
			(layer "F.Fab")
		)
		(pad "1" smd roundrect
			(at -0.485 0)
			(size 0.59 0.64)
			(layers "F.Cu" "F.Mask" "F.Paste")
			(roundrect_rratio 0.25)
			(net 629 "/Supply/VDD2_BST")
			(pintype "passive")
		)
		(pad "2" smd roundrect
			(at 0.485 0)
			(size 0.59 0.64)
			(layers "F.Cu" "F.Mask" "F.Paste")
			(roundrect_rratio 0.25)
			(net 659 "Net-(C191-Pad1)")
			(pintype "passive")
		)
	)
	(footprint "antmicro-footprints:R_0402_1005Metric"
		(layer "F.Cu")
		(at 129.95 89.074 180)
		(descr "Resistor SMD 0402")
		(tags "resistor SMD 0402")
		(property "Reference" "R133"
			(at 1.285328 2.474 180)
			(layer "F.SilkS")
			(effects
				(font
					(size 0.7 0.7)
					(thickness 0.15)
				)
				(justify left bottom)
			)
		)
		(property "Value" "R_0R_0402"
			(at 0 1.4 180)
			(layer "F.Fab")
			(effects
				(font
					(size 0.7 0.7)
					(thickness 0.15)
				)
				(justify left bottom)
			)
		)
		(property "Description" "0R resistor in 0402 package with unspecified tolerance"
			(at 0 0 180)
			(layer "F.Fab")
			(hide yes)
			(effects
				(font
					(size 1.27 1.27)
					(thickness 0.15)
				)
			)
		)
		(property "Author" "Antmicro"
			(at 259.9 178.148 0)
			(layer "F.Fab")
			(hide yes)
			(effects
				(font
					(size 1 1)
					(thickness 0.15)
				)
			)
		)
		(property "Current" "1A"
			(at 259.9 178.148 0)
			(layer "F.Fab")
			(hide yes)
			(effects
				(font
					(size 1 1)
					(thickness 0.15)
				)
			)
		)
		(property "License" "Apache-2.0"
			(at 259.9 178.148 0)
			(layer "F.Fab")
			(hide yes)
			(effects
				(font
					(size 1 1)
					(thickness 0.15)
				)
			)
		)
		(property "MPN" "ERJ2GE0R00X"
			(at 259.9 178.148 0)
			(layer "F.Fab")
			(hide yes)
			(effects
				(font
					(size 1 1)
					(thickness 0.15)
				)
			)
		)
		(property "Manufacturer" "Panasonic"
			(at 259.9 178.148 0)
			(layer "F.Fab")
			(hide yes)
			(effects
				(font
					(size 1 1)
					(thickness 0.15)
				)
			)
		)
		(property "Tolerance" ""
			(at 259.9 178.148 0)
			(layer "F.Fab")
			(hide yes)
			(effects
				(font
					(size 1 1)
					(thickness 0.15)
				)
			)
		)
		(property "Val" "0R"
			(at 259.9 178.148 0)
			(layer "F.Fab")
			(hide yes)
			(effects
				(font
					(size 1 1)
					(thickness 0.15)
				)
			)
		)
		(sheetname "Supply")
		(sheetfile "supply.kicad_sch")
		(attr smd)
		(fp_rect
			(start -0.93 -0.47)
			(end 0.93 0.47)
			(stroke
				(width 0.05)
				(type solid)
			)
			(fill no)
			(layer "F.CrtYd")
		)
		(fp_rect
			(start -0.5 -0.25)
			(end 0.5 0.25)
			(stroke
				(width 0.15)
				(type solid)
			)
			(fill no)
			(layer "F.Fab")
		)
		(pad "1" smd roundrect
			(at -0.485 0 180)
			(size 0.59 0.64)
			(layers "F.Cu" "F.Mask" "F.Paste")
			(roundrect_rratio 0.25)
			(net 5 "GND")
			(pintype "passive")
		)
		(pad "2" smd roundrect
			(at 0.485 0 180)
			(size 0.59 0.64)
			(layers "F.Cu" "F.Mask" "F.Paste")
			(roundrect_rratio 0.25)
			(net 621 "/Supply/1V1_MODE")
			(pintype "passive")
		)
	)
	(footprint "antmicro-footprints:C_0805_2012Metric"
		(layer "F.Cu")
		(at 111.2992 127)
		(descr "Capacitor SMD 0805")
		(tags "capacitor SMD 0805")
		(property "Reference" "C124"
			(at -1.5992 0.1 135)
			(layer "F.SilkS")
			(effects
				(font
					(size 0.7 0.7)
					(thickness 0.15)
				)
				(justify left bottom)
			)
		)
		(property "Value" "C_22u_0805_16V"
			(at 0 1.947 0)
			(layer "F.Fab")
			(effects
				(font
					(size 0.7 0.7)
					(thickness 0.15)
				)
				(justify left bottom)
			)
		)
		(property "Description" " "
			(at 0 0 0)
			(layer "F.Fab")
			(hide yes)
			(effects
				(font
					(size 1.27 1.27)
					(thickness 0.15)
				)
			)
		)
		(property "Author" "Antmicro"
			(at 0 0 0)
			(layer "F.Fab")
			(hide yes)
			(effects
				(font
					(size 1 1)
					(thickness 0.15)
				)
			)
		)
		(property "Dielectric" ""
			(at 0 0 0)
			(layer "F.Fab")
			(hide yes)
			(effects
				(font
					(size 1 1)
					(thickness 0.15)
				)
			)
		)
		(property "License" "Apache-2.0"
			(at 0 0 0)
			(layer "F.Fab")
			(hide yes)
			(effects
				(font
					(size 1 1)
					(thickness 0.15)
				)
			)
		)
		(property "MPN" "GRT21BR61C226ME13L"
			(at 0 0 0)
			(layer "F.Fab")
			(hide yes)
			(effects
				(font
					(size 1 1)
					(thickness 0.15)
				)
			)
		)
		(property "Manufacturer" "Murata"
			(at 0 0 0)
			(layer "F.Fab")
			(hide yes)
			(effects
				(font
					(size 1 1)
					(thickness 0.15)
				)
			)
		)
		(property "Val" "22u/16V"
			(at 0 0 0)
			(layer "F.Fab")
			(hide yes)
			(effects
				(font
					(size 1 1)
					(thickness 0.15)
				)
			)
		)
		(property "Voltage" ""
			(at 0 0 0)
			(layer "F.Fab")
			(hide yes)
			(effects
				(font
					(size 1 1)
					(thickness 0.15)
				)
			)
		)
		(sheetname "Supply")
		(sheetfile "supply.kicad_sch")
		(attr smd)
		(fp_line
			(start -0.3 -0.8)
			(end 0.3 -0.8)
			(stroke
				(width 0.15)
				(type solid)
			)
			(layer "F.SilkS")
		)
		(fp_line
			(start -0.3 0.8)
			(end 0.3 0.8)
			(stroke
				(width 0.15)
				(type solid)
			)
			(layer "F.SilkS")
		)
		(fp_rect
			(start -1.9 -0.93)
			(end 1.9 0.93)
			(stroke
				(width 0.05)
				(type solid)
			)
			(fill no)
			(layer "F.CrtYd")
		)
		(fp_rect
			(start -0.95 -0.675)
			(end 0.95 0.675)
			(stroke
				(width 0.15)
				(type solid)
			)
			(fill no)
			(layer "F.Fab")
		)
		(pad "1" smd rect
			(at -1.05 0)
			(size 1.2 1.2)
			(layers "F.Cu" "F.Mask" "F.Paste")
			(net 224 "VIN")
			(pintype "passive")
		)
		(pad "2" smd rect
			(at 1.05 0)
			(size 1.2 1.2)
			(layers "F.Cu" "F.Mask" "F.Paste")
			(net 5 "GND")
			(pintype "passive")
		)
	)
	(footprint "antmicro-footprints:C_0402_1005Metric"
		(layer "F.Cu")
		(at 115.225 102.449 180)
		(descr "Capacitor SMD 0402")
		(tags "capacitor SMD 0402")
		(property "Reference" "C152"
			(at 1.925 -1.251 180)
			(layer "F.SilkS")
			(effects
				(font
					(size 0.7 0.7)
					(thickness 0.15)
				)
				(justify left bottom)
			)
		)
		(property "Value" "C_10u_0402"
			(at 0 1.4 180)
			(layer "F.Fab")
			(effects
				(font
					(size 0.7 0.7)
					(thickness 0.15)
				)
				(justify left bottom)
			)
		)
		(property "Description" " "
			(at 0 0 180)
			(layer "F.Fab")
			(hide yes)
			(effects
				(font
					(size 1.27 1.27)
					(thickness 0.15)
				)
			)
		)
		(property "Author" "Antmicro"
			(at 230.45 204.898 0)
			(layer "F.Fab")
			(hide yes)
			(effects
				(font
					(size 1 1)
					(thickness 0.15)
				)
			)
		)
		(property "Dielectric" ""
			(at 230.45 204.898 0)
			(layer "F.Fab")
			(hide yes)
			(effects
				(font
					(size 1 1)
					(thickness 0.15)
				)
			)
		)
		(property "License" "Apache-2.0"
			(at 230.45 204.898 0)
			(layer "F.Fab")
			(hide yes)
			(effects
				(font
					(size 1 1)
					(thickness 0.15)
				)
			)
		)
		(property "MPN" "CC0402MRX5R5BB106"
			(at 230.45 204.898 0)
			(layer "F.Fab")
			(hide yes)
			(effects
				(font
					(size 1 1)
					(thickness 0.15)
				)
			)
		)
		(property "Manufacturer" "Yaego"
			(at 230.45 204.898 0)
			(layer "F.Fab")
			(hide yes)
			(effects
				(font
					(size 1 1)
					(thickness 0.15)
				)
			)
		)
		(property "Val" "10u"
			(at 230.45 204.898 0)
			(layer "F.Fab")
			(hide yes)
			(effects
				(font
					(size 1 1)
					(thickness 0.15)
				)
			)
		)
		(property "Voltage" ""
			(at 230.45 204.898 0)
			(layer "F.Fab")
			(hide yes)
			(effects
				(font
					(size 1 1)
					(thickness 0.15)
				)
			)
		)
		(sheetname "Supply")
		(sheetfile "supply.kicad_sch")
		(attr smd)
		(fp_rect
			(start -0.94 -0.47)
			(end 0.94 0.47)
			(stroke
				(width 0.05)
				(type solid)
			)
			(fill no)
			(layer "F.CrtYd")
		)
		(fp_rect
			(start -0.499 -0.249)
			(end 0.499 0.249)
			(stroke
				(width 0.15)
				(type solid)
			)
			(fill no)
			(layer "F.Fab")
		)
		(pad "1" smd roundrect
			(at -0.484 0 180)
			(size 0.59 0.64)
			(layers "F.Cu" "F.Mask" "F.Paste")
			(roundrect_rratio 0.25)
			(net 463 "VCC5V0_INT")
			(pintype "passive")
		)
		(pad "2" smd roundrect
			(at 0.484 0 180)
			(size 0.59 0.64)
			(layers "F.Cu" "F.Mask" "F.Paste")
			(roundrect_rratio 0.25)
			(net 5 "GND")
			(pintype "passive")
		)
	)
	(footprint "antmicro-footprints:C_0805_2012Metric"
		(layer "F.Cu")
		(at 111.2992 125.125)
		(descr "Capacitor SMD 0805")
		(tags "capacitor SMD 0805")
		(property "Reference" "C123"
			(at -1.5992 0.1 135)
			(layer "F.SilkS")
			(effects
				(font
					(size 0.7 0.7)
					(thickness 0.15)
				)
				(justify left bottom)
			)
		)
		(property "Value" "C_22u_0805_16V"
			(at 0 1.947 0)
			(layer "F.Fab")
			(effects
				(font
					(size 0.7 0.7)
					(thickness 0.15)
				)
				(justify left bottom)
			)
		)
		(property "Description" " "
			(at 0 0 0)
			(layer "F.Fab")
			(hide yes)
			(effects
				(font
					(size 1.27 1.27)
					(thickness 0.15)
				)
			)
		)
		(property "Author" "Antmicro"
			(at 0 0 0)
			(layer "F.Fab")
			(hide yes)
			(effects
				(font
					(size 1 1)
					(thickness 0.15)
				)
			)
		)
		(property "Dielectric" ""
			(at 0 0 0)
			(layer "F.Fab")
			(hide yes)
			(effects
				(font
					(size 1 1)
					(thickness 0.15)
				)
			)
		)
		(property "License" "Apache-2.0"
			(at 0 0 0)
			(layer "F.Fab")
			(hide yes)
			(effects
				(font
					(size 1 1)
					(thickness 0.15)
				)
			)
		)
		(property "MPN" "GRT21BR61C226ME13L"
			(at 0 0 0)
			(layer "F.Fab")
			(hide yes)
			(effects
				(font
					(size 1 1)
					(thickness 0.15)
				)
			)
		)
		(property "Manufacturer" "Murata"
			(at 0 0 0)
			(layer "F.Fab")
			(hide yes)
			(effects
				(font
					(size 1 1)
					(thickness 0.15)
				)
			)
		)
		(property "Val" "22u/16V"
			(at 0 0 0)
			(layer "F.Fab")
			(hide yes)
			(effects
				(font
					(size 1 1)
					(thickness 0.15)
				)
			)
		)
		(property "Voltage" ""
			(at 0 0 0)
			(layer "F.Fab")
			(hide yes)
			(effects
				(font
					(size 1 1)
					(thickness 0.15)
				)
			)
		)
		(sheetname "Supply")
		(sheetfile "supply.kicad_sch")
		(attr smd)
		(fp_line
			(start -0.3 -0.8)
			(end 0.3 -0.8)
			(stroke
				(width 0.15)
				(type solid)
			)
			(layer "F.SilkS")
		)
		(fp_line
			(start -0.3 0.8)
			(end 0.3 0.8)
			(stroke
				(width 0.15)
				(type solid)
			)
			(layer "F.SilkS")
		)
		(fp_rect
			(start -1.9 -0.93)
			(end 1.9 0.93)
			(stroke
				(width 0.05)
				(type solid)
			)
			(fill no)
			(layer "F.CrtYd")
		)
		(fp_rect
			(start -0.95 -0.675)
			(end 0.95 0.675)
			(stroke
				(width 0.15)
				(type solid)
			)
			(fill no)
			(layer "F.Fab")
		)
		(pad "1" smd rect
			(at -1.05 0)
			(size 1.2 1.2)
			(layers "F.Cu" "F.Mask" "F.Paste")
			(net 224 "VIN")
			(pintype "passive")
		)
		(pad "2" smd rect
			(at 1.05 0)
			(size 1.2 1.2)
			(layers "F.Cu" "F.Mask" "F.Paste")
			(net 5 "GND")
			(pintype "passive")
		)
	)
	(footprint "antmicro-footprints:C_0402_1005Metric"
		(layer "F.Cu")
		(at 188.25 115.885 -90)
		(descr "Capacitor SMD 0402")
		(tags "capacitor SMD 0402")
		(property "Reference" "C160"
			(at -0.785 -0.45 90)
			(layer "F.SilkS")
			(effects
				(font
					(size 0.7 0.7)
					(thickness 0.15)
				)
				(justify left bottom)
			)
		)
		(property "Value" "C_100n_6V3_0402"
			(at 0 1.4 270)
			(layer "F.Fab")
			(effects
				(font
					(size 0.7 0.7)
					(thickness 0.15)
				)
				(justify left bottom)
			)
		)
		(property "Description" " "
			(at 0 0 270)
			(layer "F.Fab")
			(hide yes)
			(effects
				(font
					(size 1.27 1.27)
					(thickness 0.15)
				)
			)
		)
		(property "Author" "Antmicro"
			(at 72.365 304.135 0)
			(layer "F.Fab")
			(hide yes)
			(effects
				(font
					(size 1 1)
					(thickness 0.15)
				)
			)
		)
		(property "Dielectric" ""
			(at 72.365 304.135 0)
			(layer "F.Fab")
			(hide yes)
			(effects
				(font
					(size 1 1)
					(thickness 0.15)
				)
			)
		)
		(property "License" "Apache-2.0"
			(at 72.365 304.135 0)
			(layer "F.Fab")
			(hide yes)
			(effects
				(font
					(size 1 1)
					(thickness 0.15)
				)
			)
		)
		(property "MPN" "0402X104K6R3CT"
			(at 72.365 304.135 0)
			(layer "F.Fab")
			(hide yes)
			(effects
				(font
					(size 1 1)
					(thickness 0.15)
				)
			)
		)
		(property "Manufacturer" "Walsin"
			(at 72.365 304.135 0)
			(layer "F.Fab")
			(hide yes)
			(effects
				(font
					(size 1 1)
					(thickness 0.15)
				)
			)
		)
		(property "Val" "100n"
			(at 72.365 304.135 0)
			(layer "F.Fab")
			(hide yes)
			(effects
				(font
					(size 1 1)
					(thickness 0.15)
				)
			)
		)
		(property "Voltage" ""
			(at 72.365 304.135 0)
			(layer "F.Fab")
			(hide yes)
			(effects
				(font
					(size 1 1)
					(thickness 0.15)
				)
			)
		)
		(sheetname "Supply")
		(sheetfile "supply.kicad_sch")
		(attr smd)
		(fp_rect
			(start -0.94 -0.47)
			(end 0.94 0.47)
			(stroke
				(width 0.05)
				(type solid)
			)
			(fill no)
			(layer "F.CrtYd")
		)
		(fp_rect
			(start -0.499 -0.249)
			(end 0.499 0.249)
			(stroke
				(width 0.15)
				(type solid)
			)
			(fill no)
			(layer "F.Fab")
		)
		(pad "1" smd roundrect
			(at -0.484 0 270)
			(size 0.59 0.64)
			(layers "F.Cu" "F.Mask" "F.Paste")
			(roundrect_rratio 0.25)
			(net 586 "/Supply/1V2_SW")
			(pintype "passive")
		)
		(pad "2" smd roundrect
			(at 0.484 0 270)
			(size 0.59 0.64)
			(layers "F.Cu" "F.Mask" "F.Paste")
			(roundrect_rratio 0.25)
			(net 585 "/Supply/1V2_BST")
			(pintype "passive")
		)
	)
	(footprint "antmicro-footprints:TP_SMD_1mm"
		(layer "F.Cu")
		(at 144.725 85.1982 180)
		(property "Reference" "TP19"
			(at 1.4 4.3982 180)
			(layer "F.SilkS")
			(effects
				(font
					(size 0.7 0.7)
					(thickness 0.15)
				)
				(justify left bottom)
			)
		)
		(property "Value" "TP_1mm_SMD"
			(at 0 1.4 180)
			(layer "F.Fab")
			(effects
				(font
					(size 0.7 0.7)
					(thickness 0.15)
				)
				(justify left bottom)
			)
		)
		(property "Description" "Test Point 1mm"
			(at 0 0 180)
			(layer "F.Fab")
			(hide yes)
			(effects
				(font
					(size 1.27 1.27)
					(thickness 0.15)
				)
			)
		)
		(property "Author" "Antmicro"
			(at 289.45 170.3964 0)
			(layer "F.Fab")
			(hide yes)
			(effects
				(font
					(size 1 1)
					(thickness 0.15)
				)
			)
		)
		(property "License" "Apache-2.0"
			(at 289.45 170.3964 0)
			(layer "F.Fab")
			(hide yes)
			(effects
				(font
					(size 1 1)
					(thickness 0.15)
				)
			)
		)
		(property "MPN" ""
			(at 289.45 170.3964 0)
			(layer "F.Fab")
			(hide yes)
			(effects
				(font
					(size 1 1)
					(thickness 0.15)
				)
			)
		)
		(property "Manufacturer" ""
			(at 289.45 170.3964 0)
			(layer "F.Fab")
			(hide yes)
			(effects
				(font
					(size 1 1)
					(thickness 0.15)
				)
			)
		)
		(sheetname "Supply")
		(sheetfile "supply.kicad_sch")
		(attr exclude_from_pos_files)
		(pad "1" smd circle
			(at 0 0 180)
			(size 1 1)
			(layers "F.Cu" "F.Mask")
			(net 465 "1V0_SYS")
			(pinfunction "1")
			(pintype "passive")
		)
	)
	(footprint "antmicro-footprints:R_0402_1005Metric"
		(layer "F.Cu")
		(at 115.3492 112.6)
		(descr "Resistor SMD 0402")
		(tags "resistor SMD 0402")
		(property "Reference" "R100"
			(at -1.8492 -1.5 0)
			(layer "F.SilkS")
			(effects
				(font
					(size 0.7 0.7)
					(thickness 0.15)
				)
				(justify left bottom)
			)
		)
		(property "Value" "R_100k_0402"
			(at 0 1.4 0)
			(layer "F.Fab")
			(effects
				(font
					(size 0.7 0.7)
					(thickness 0.15)
				)
				(justify left bottom)
			)
		)
		(property "Description" "100k resistor in 0402 package with 1% tolerance"
			(at 0 0 0)
			(layer "F.Fab")
			(hide yes)
			(effects
				(font
					(size 1.27 1.27)
					(thickness 0.15)
				)
			)
		)
		(property "Author" "Antmicro"
			(at 0 0 0)
			(layer "F.Fab")
			(hide yes)
			(effects
				(font
					(size 1 1)
					(thickness 0.15)
				)
			)
		)
		(property "License" "Apache-2.0"
			(at 0 0 0)
			(layer "F.Fab")
			(hide yes)
			(effects
				(font
					(size 1 1)
					(thickness 0.15)
				)
			)
		)
		(property "MPN" "CR0402-FX-1003GLF"
			(at 0 0 0)
			(layer "F.Fab")
			(hide yes)
			(effects
				(font
					(size 1 1)
					(thickness 0.15)
				)
			)
		)
		(property "Manufacturer" "Bourns"
			(at 0 0 0)
			(layer "F.Fab")
			(hide yes)
			(effects
				(font
					(size 1 1)
					(thickness 0.15)
				)
			)
		)
		(property "Tolerance" "1%"
			(at 0 0 0)
			(layer "F.Fab")
			(hide yes)
			(effects
				(font
					(size 1 1)
					(thickness 0.15)
				)
			)
		)
		(property "Val" "100k"
			(at 0 0 0)
			(layer "F.Fab")
			(hide yes)
			(effects
				(font
					(size 1 1)
					(thickness 0.15)
				)
			)
		)
		(sheetname "Supply")
		(sheetfile "supply.kicad_sch")
		(attr smd)
		(fp_rect
			(start -0.93 -0.47)
			(end 0.93 0.47)
			(stroke
				(width 0.05)
				(type solid)
			)
			(fill no)
			(layer "F.CrtYd")
		)
		(fp_rect
			(start -0.5 -0.25)
			(end 0.5 0.25)
			(stroke
				(width 0.15)
				(type solid)
			)
			(fill no)
			(layer "F.Fab")
		)
		(pad "1" smd roundrect
			(at -0.485 0)
			(size 0.59 0.64)
			(layers "F.Cu" "F.Mask" "F.Paste")
			(roundrect_rratio 0.25)
			(net 463 "VCC5V0_INT")
			(pintype "passive")
		)
		(pad "2" smd roundrect
			(at 0.485 0)
			(size 0.59 0.64)
			(layers "F.Cu" "F.Mask" "F.Paste")
			(roundrect_rratio 0.25)
			(net 466 "SYS_ON")
			(pintype "passive")
		)
	)
)
